(kicad_pcb
	(version 20260206)
	(generator "pcbnew")
	(generator_version "10.0")
	(general
		(thickness 1.6)
		(legacy_teardrops no)
	)
	(paper "A4")
	(title_block
		(title "Bryce Canyon_IOM_M2_16342-2_OCP.brd")
		(comment 1 "Bryce Canyon / footprints 545-552 of 1146")
	)
	(layers
		(0 "F.Cu" signal "TOP")
		(4 "In1.Cu" signal "L2GND")
		(6 "In2.Cu" signal "L3")
		(8 "In3.Cu" signal "L4VCC")
		(10 "In4.Cu" signal "L5VCC")
		(12 "In5.Cu" signal "L6")
		(14 "In6.Cu" signal "L7GND")
		(2 "B.Cu" signal "BOTTOM")
		(9 "F.Adhes" user "F.Adhesive")
		(11 "B.Adhes" user "B.Adhesive")
		(13 "F.Paste" user "Package Geometry/Pastemask Top")
		(15 "B.Paste" user "Package Geometry/Pastemask Bottom")
		(5 "F.SilkS" user "Ref Des/Silkscreen Top")
		(7 "B.SilkS" user "Ref Des/Silkscreen Bottom")
		(1 "F.Mask" user "Board Geometry/Soldermask Top")
		(3 "B.Mask" user "Board Geometry/Soldermask Bottom")
		(17 "Dwgs.User" user "User.Drawings")
		(19 "Cmts.User" user "User.Comments")
		(21 "Eco1.User" user "User.Eco1")
		(23 "Eco2.User" user "User.Eco2")
		(25 "Edge.Cuts" user "Board Geometry/Outline")
		(27 "Margin" user)
		(31 "F.CrtYd" user "Package Geometry/Place Bound Top")
		(29 "B.CrtYd" user "Package Geometry/Place Bound Bottom")
		(35 "F.Fab" user "Ref Des/Assembly Top")
		(33 "B.Fab" user "Ref Des/Assembly Bottom")
	)
	(footprint ""
		(layer "F.Cu")
		(at 202.946 -141.097 -135)
		(property "Reference" "VIA53"
			(at 0 0 225)
			(layer "F.SilkS")
			(hide yes)
			(effects
				(font
					(size 1.27 1.27)
				)
			)
		)
		(property "Value" "85OHM-8L-1D6MM-L16L18-GP"
			(at 4.064105 0.609655 225)
			(unlocked yes)
			(layer "F.Fab")
			(hide yes)
			(effects
				(font
					(size 1.016 1.016)
					(thickness 0.1524)
				)
			)
		)
		(property "Device Type" "VIA-PCIE-4P-368076"
			(at 4.064105 -0.914474 225)
			(unlocked yes)
			(layer "F.Fab")
			(hide yes)
			(effects
				(font
					(size 1.016 1.016)
					(thickness 0.1524)
				)
			)
		)
		(duplicate_pad_numbers_are_jumpers no)
		(fp_poly
			(pts
				(xy -1.841491 -0.381057) (xy 1.841509 -0.381058) (xy 1.841508 0.380942) (xy -1.841491 0.380942)
			)
			(stroke
				(width 0)
				(type default)
			)
			(fill no)
			(layer "F.CrtYd")
		)
		(fp_poly
			(pts
				(xy -1.841491 -0.381057) (xy 1.841509 -0.381058) (xy 1.841508 0.380942) (xy -1.841491 0.380942)
			)
			(stroke
				(width 0)
				(type default)
			)
			(fill no)
			(layer "F.Fab")
		)
		(pad "1" thru_hole circle
			(at -1.460499 0 225)
			(size 0.508 0.508)
			(drill 0.254)
			(layers "*.Cu" "*.Mask")
			(remove_unused_layers no)
			(net "GND")
			(clearance 0.127)
			(thermal_gap 0.127)
		)
		(pad "2" thru_hole circle
			(at -0.4445 0 225)
			(size 0.508 0.508)
			(drill 0.254)
			(layers "*.Cu" "*.Mask")
			(remove_unused_layers no)
			(net "PCIE_IOM_TO_COMP_9_DP")
			(clearance 0.127)
			(thermal_gap 0.127)
		)
		(pad "3" thru_hole circle
			(at 0.4445 0 225)
			(size 0.508 0.508)
			(drill 0.254)
			(layers "*.Cu" "*.Mask")
			(remove_unused_layers no)
			(net "PCIE_IOM_TO_COMP_9_DN")
			(clearance 0.127)
			(thermal_gap 0.127)
		)
		(pad "4" thru_hole circle
			(at 1.460499 0 225)
			(size 0.508 0.508)
			(drill 0.254)
			(layers "*.Cu" "*.Mask")
			(remove_unused_layers no)
			(net "GND")
			(clearance 0.127)
			(thermal_gap 0.127)
		)
	)
	(footprint ""
		(layer "F.Cu")
		(at 58.407808 -159.54502)
		(property "Reference" "R391"
			(at 0 0 0)
			(layer "F.SilkS")
			(hide yes)
			(effects
				(font
					(size 1.27 1.27)
				)
			)
		)
		(property "Value" "4K7R2F-GP"
			(at 0.064008 -3.993896 0)
			(unlocked yes)
			(layer "F.Fab")
			(hide yes)
			(effects
				(font
					(size 1.016 1.016)
					(thickness 0.1524)
				)
			)
		)
		(property "Device Type" "R402H16"
			(at 0.064008 -5.517896 0)
			(unlocked yes)
			(layer "F.Fab")
			(hide yes)
			(effects
				(font
					(size 1.016 1.016)
					(thickness 0.1524)
				)
			)
		)
		(duplicate_pad_numbers_are_jumpers no)
		(fp_line
			(start -0.508 -0.9398)
			(end -0.508 0.9398)
			(stroke
				(width 0.1524)
				(type default)
			)
			(layer "F.SilkS")
		)
		(fp_line
			(start 0.508 -0.9398)
			(end -0.508 -0.9398)
			(stroke
				(width 0.1524)
				(type default)
			)
			(layer "F.SilkS")
		)
		(fp_rect
			(start -0.508 0.9398)
			(end 0.508 -0.9398)
			(stroke
				(width 0)
				(type default)
			)
			(fill no)
			(layer "F.CrtYd")
		)
		(fp_rect
			(start -0.508 0.9398)
			(end 0.508 -0.9398)
			(stroke
				(width 0)
				(type default)
			)
			(fill no)
			(layer "F.Fab")
		)
		(pad "1" smd custom
			(at 0 -0.4445)
			(size 0.1397 0.1397)
			(layers "F.Cu" "F.Mask" "F.Paste")
			(net "P3V3_STBY")
			(options
				(clearance outline)
				(anchor circle)
			)
			(primitives
				(gr_poly
					(pts
						(arc
							(start -0.1778 -0.2794)
							(mid -0.249642 -0.249642)
							(end -0.2794 -0.1778)
						)
						(arc
							(start -0.2794 0.1778)
							(mid -0.249642 0.249642)
							(end -0.1778 0.2794)
						)
						(arc
							(start 0.1778 0.2794)
							(mid 0.249642 0.249642)
							(end 0.2794 0.1778)
						)
						(arc
							(start 0.2794 -0.1778)
							(mid 0.249642 -0.249642)
							(end 0.1778 -0.2794)
						)
					)
					(width 0)
					(fill yes)
				)
			)
		)
		(pad "2" smd custom
			(at 0 0.4445)
			(size 0.1397 0.1397)
			(layers "F.Cu" "F.Mask" "F.Paste")
			(net "MAC2_TXD0")
			(options
				(clearance outline)
				(anchor circle)
			)
			(primitives
				(gr_poly
					(pts
						(arc
							(start -0.1778 -0.2794)
							(mid -0.249642 -0.249642)
							(end -0.2794 -0.1778)
						)
						(arc
							(start -0.2794 0.1778)
							(mid -0.249642 0.249642)
							(end -0.1778 0.2794)
						)
						(arc
							(start 0.1778 0.2794)
							(mid 0.249642 0.249642)
							(end 0.2794 0.1778)
						)
						(arc
							(start 0.2794 -0.1778)
							(mid 0.249642 -0.249642)
							(end 0.1778 -0.2794)
						)
					)
					(width 0)
					(fill yes)
				)
			)
		)
	)
	(footprint ""
		(layer "F.Cu")
		(at 56.362092 -157.129988 90)
		(property "Reference" "TP53"
			(at 0 0 90)
			(layer "F.SilkS")
			(hide yes)
			(effects
				(font
					(size 1.27 1.27)
				)
			)
		)
		(property "Value" "TPAD28-2-GP"
			(at -0.0127 -1.6637 90)
			(unlocked yes)
			(layer "F.Fab")
			(hide yes)
			(effects
				(font
					(size 1.016 1.016)
					(thickness 0.1524)
				)
			)
		)
		(property "Device Type" "TPAD28"
			(at -0.0127 -3.1877 90)
			(unlocked yes)
			(layer "F.Fab")
			(hide yes)
			(effects
				(font
					(size 1.016 1.016)
					(thickness 0.1524)
				)
			)
		)
		(duplicate_pad_numbers_are_jumpers no)
		(fp_poly
			(pts
				(arc
					(start 0 0.3556)
					(mid 0 -0.3556)
					(end 0 0.3556)
				)
			)
			(stroke
				(width 0)
				(type default)
			)
			(fill no)
			(layer "F.CrtYd")
		)
		(fp_poly
			(pts
				(arc
					(start 0 0.6096)
					(mid 0 -0.6096)
					(end 0 0.6096)
				)
			)
			(stroke
				(width 0)
				(type default)
			)
			(fill no)
			(layer "F.Fab")
		)
		(pad "1" smd circle
			(at 0 0 90)
			(size 0.7112 0.7112)
			(layers "F.Cu" "F.Mask" "F.Paste")
			(net "TP_BMC_GPIOT6")
		)
	)
	(footprint ""
		(layer "F.Cu")
		(at 31.70428 -186.992514 180)
		(property "Reference" "C173"
			(at 0 0 180)
			(layer "F.SilkS")
			(hide yes)
			(effects
				(font
					(size 1.27 1.27)
				)
			)
		)
		(property "Value" "SC10U16V5KX-7-GP-U"
			(at -0.0762 -6.1214 180)
			(unlocked yes)
			(layer "F.Fab")
			(hide yes)
			(effects
				(font
					(size 1.016 1.016)
					(thickness 0.1524)
				)
			)
		)
		(property "Device Type" "C805H58"
			(at -0.0762 -8.1534 180)
			(unlocked yes)
			(layer "F.Fab")
			(hide yes)
			(effects
				(font
					(size 1.016 1.016)
					(thickness 0.1524)
				)
			)
		)
		(duplicate_pad_numbers_are_jumpers no)
		(fp_line
			(start 0.635 0)
			(end -0.635 0)
			(stroke
				(width 0.508)
				(type default)
			)
			(layer "F.SilkS")
		)
		(fp_rect
			(start -0.9652 1.778)
			(end 0.9652 -1.778)
			(stroke
				(width 0)
				(type default)
			)
			(fill no)
			(layer "F.CrtYd")
		)
		(fp_poly
			(pts
				(xy -0.9652 -1.778) (xy 0.9652 -1.778) (xy 0.9652 1.778) (xy -0.9652 1.778)
			)
			(stroke
				(width 0)
				(type default)
			)
			(fill no)
			(layer "F.Fab")
		)
		(pad "1" smd rect
			(at 0 -0.9652 180)
			(size 1.397 1.143)
			(layers "F.Cu" "F.Mask" "F.Paste")
			(net "P12V_STBY_VIN_PU2")
		)
		(pad "2" smd rect
			(at 0 0.9652 180)
			(size 1.397 1.143)
			(layers "F.Cu" "F.Mask" "F.Paste")
			(net "GND")
		)
	)
	(footprint ""
		(layer "F.Cu")
		(at 83.82 -148.59 90)
		(property "Reference" "C37"
			(at 0 0 90)
			(layer "F.SilkS")
			(hide yes)
			(effects
				(font
					(size 1.27 1.27)
				)
			)
		)
		(property "Value" "SCD1U16V2KX-3GP"
			(at 1.1811 -2.7051 90)
			(unlocked yes)
			(layer "F.Fab")
			(hide yes)
			(effects
				(font
					(size 1.016 1.016)
					(thickness 0.1524)
				)
			)
		)
		(property "Device Type" "C402H22"
			(at 1.1811 -4.2291 90)
			(unlocked yes)
			(layer "F.Fab")
			(hide yes)
			(effects
				(font
					(size 1.016 1.016)
					(thickness 0.1524)
				)
			)
		)
		(duplicate_pad_numbers_are_jumpers no)
		(fp_rect
			(start -0.4318 0.9525)
			(end 0.4318 -0.9525)
			(stroke
				(width 0)
				(type default)
			)
			(fill no)
			(layer "F.CrtYd")
		)
		(fp_rect
			(start -0.4318 0.9525)
			(end 0.4318 -0.9525)
			(stroke
				(width 0)
				(type default)
			)
			(fill no)
			(layer "F.Fab")
		)
		(pad "1" smd custom
			(at 0 -0.4445 90)
			(size 0.1524 0.1524)
			(layers "F.Cu" "F.Mask" "F.Paste")
			(net "P3V3_STBY")
			(options
				(clearance outline)
				(anchor circle)
			)
			(primitives
				(gr_poly
					(pts
						(arc
							(start 0.3048 -0.2032)
							(mid 0.275042 -0.275042)
							(end 0.2032 -0.3048)
						)
						(arc
							(start -0.2032 -0.3048)
							(mid -0.275042 -0.275042)
							(end -0.3048 -0.2032)
						)
						(arc
							(start -0.3048 0.2032)
							(mid -0.275042 0.275042)
							(end -0.2032 0.3048)
						)
						(arc
							(start 0.2032 0.3048)
							(mid 0.275042 0.275042)
							(end 0.3048 0.2032)
						)
					)
					(width 0)
					(fill yes)
				)
			)
		)
		(pad "2" smd custom
			(at 0 0.4445 90)
			(size 0.1524 0.1524)
			(layers "F.Cu" "F.Mask" "F.Paste")
			(net "GND")
			(options
				(clearance outline)
				(anchor circle)
			)
			(primitives
				(gr_poly
					(pts
						(arc
							(start 0.3048 -0.2032)
							(mid 0.275042 -0.275042)
							(end 0.2032 -0.3048)
						)
						(arc
							(start -0.2032 -0.3048)
							(mid -0.275042 -0.275042)
							(end -0.3048 -0.2032)
						)
						(arc
							(start -0.3048 0.2032)
							(mid -0.275042 0.275042)
							(end -0.2032 0.3048)
						)
						(arc
							(start 0.2032 0.3048)
							(mid 0.275042 0.275042)
							(end 0.3048 0.2032)
						)
					)
					(width 0)
					(fill yes)
				)
			)
		)
	)
	(footprint ""
		(layer "F.Cu")
		(at 43.8658 -158.5976)
		(property "Reference" "R174"
			(at 0 0 0)
			(layer "F.SilkS")
			(hide yes)
			(effects
				(font
					(size 1.27 1.27)
				)
			)
		)
		(property "Value" "0R2J-2-GP"
			(at 0.064008 -3.993896 0)
			(unlocked yes)
			(layer "F.Fab")
			(hide yes)
			(effects
				(font
					(size 1.016 1.016)
					(thickness 0.1524)
				)
			)
		)
		(property "Device Type" "R402H16"
			(at 0.064008 -5.517896 0)
			(unlocked yes)
			(layer "F.Fab")
			(hide yes)
			(effects
				(font
					(size 1.016 1.016)
					(thickness 0.1524)
				)
			)
		)
		(duplicate_pad_numbers_are_jumpers no)
		(fp_line
			(start -0.508 -0.9398)
			(end -0.508 0.9398)
			(stroke
				(width 0.1524)
				(type default)
			)
			(layer "F.SilkS")
		)
		(fp_line
			(start 0.508 -0.9398)
			(end -0.508 -0.9398)
			(stroke
				(width 0.1524)
				(type default)
			)
			(layer "F.SilkS")
		)
		(fp_rect
			(start -0.508 0.9398)
			(end 0.508 -0.9398)
			(stroke
				(width 0)
				(type default)
			)
			(fill no)
			(layer "F.CrtYd")
		)
		(fp_rect
			(start -0.508 0.9398)
			(end 0.508 -0.9398)
			(stroke
				(width 0)
				(type default)
			)
			(fill no)
			(layer "F.Fab")
		)
		(pad "1" smd custom
			(at 0 -0.4445)
			(size 0.1397 0.1397)
			(layers "F.Cu" "F.Mask" "F.Paste")
			(net "I2C_M2_1_SDA")
			(options
				(clearance outline)
				(anchor circle)
			)
			(primitives
				(gr_poly
					(pts
						(arc
							(start -0.1778 -0.2794)
							(mid -0.249642 -0.249642)
							(end -0.2794 -0.1778)
						)
						(arc
							(start -0.2794 0.1778)
							(mid -0.249642 0.249642)
							(end -0.1778 0.2794)
						)
						(arc
							(start 0.1778 0.2794)
							(mid 0.249642 0.249642)
							(end 0.2794 0.1778)
						)
						(arc
							(start 0.2794 -0.1778)
							(mid 0.249642 -0.249642)
							(end 0.1778 -0.2794)
						)
					)
					(width 0)
					(fill yes)
				)
			)
		)
		(pad "2" smd custom
			(at 0 0.4445)
			(size 0.1397 0.1397)
			(layers "F.Cu" "F.Mask" "F.Paste")
			(net "BMC_SMB8_DAT")
			(options
				(clearance outline)
				(anchor circle)
			)
			(primitives
				(gr_poly
					(pts
						(arc
							(start -0.1778 -0.2794)
							(mid -0.249642 -0.249642)
							(end -0.2794 -0.1778)
						)
						(arc
							(start -0.2794 0.1778)
							(mid -0.249642 0.249642)
							(end -0.1778 0.2794)
						)
						(arc
							(start 0.1778 0.2794)
							(mid 0.249642 0.249642)
							(end 0.2794 0.1778)
						)
						(arc
							(start 0.2794 -0.1778)
							(mid 0.249642 -0.249642)
							(end 0.1778 -0.2794)
						)
					)
					(width 0)
					(fill yes)
				)
			)
		)
	)
	(footprint ""
		(layer "F.Cu")
		(at 51.8414 -162.4838)
		(property "Reference" "R409"
			(at 0 0 0)
			(layer "F.SilkS")
			(hide yes)
			(effects
				(font
					(size 1.27 1.27)
				)
			)
		)
		(property "Value" "1K4R2F-1-GP"
			(at 0.064008 -3.993896 0)
			(unlocked yes)
			(layer "F.Fab")
			(hide yes)
			(effects
				(font
					(size 1.016 1.016)
					(thickness 0.1524)
				)
			)
		)
		(property "Device Type" "R402H16"
			(at 0.064008 -5.517896 0)
			(unlocked yes)
			(layer "F.Fab")
			(hide yes)
			(effects
				(font
					(size 1.016 1.016)
					(thickness 0.1524)
				)
			)
		)
		(duplicate_pad_numbers_are_jumpers no)
		(fp_line
			(start -0.508 -0.9398)
			(end -0.508 0.9398)
			(stroke
				(width 0.1524)
				(type default)
			)
			(layer "F.SilkS")
		)
		(fp_line
			(start 0.508 -0.9398)
			(end -0.508 -0.9398)
			(stroke
				(width 0.1524)
				(type default)
			)
			(layer "F.SilkS")
		)
		(fp_rect
			(start -0.508 0.9398)
			(end 0.508 -0.9398)
			(stroke
				(width 0)
				(type default)
			)
			(fill no)
			(layer "F.CrtYd")
		)
		(fp_rect
			(start -0.508 0.9398)
			(end 0.508 -0.9398)
			(stroke
				(width 0)
				(type default)
			)
			(fill no)
			(layer "F.Fab")
		)
		(pad "1" smd custom
			(at 0 -0.4445)
			(size 0.1397 0.1397)
			(layers "F.Cu" "F.Mask" "F.Paste")
			(net "P3V3")
			(options
				(clearance outline)
				(anchor circle)
			)
			(primitives
				(gr_poly
					(pts
						(arc
							(start -0.1778 -0.2794)
							(mid -0.249642 -0.249642)
							(end -0.2794 -0.1778)
						)
						(arc
							(start -0.2794 0.1778)
							(mid -0.249642 0.249642)
							(end -0.1778 0.2794)
						)
						(arc
							(start 0.1778 0.2794)
							(mid 0.249642 0.249642)
							(end 0.2794 0.1778)
						)
						(arc
							(start 0.2794 -0.1778)
							(mid 0.249642 -0.249642)
							(end 0.1778 -0.2794)
						)
					)
					(width 0)
					(fill yes)
				)
			)
		)
		(pad "2" smd custom
			(at 0 0.4445)
			(size 0.1397 0.1397)
			(layers "F.Cu" "F.Mask" "F.Paste")
			(net "ADC_P3V3")
			(options
				(clearance outline)
				(anchor circle)
			)
			(primitives
				(gr_poly
					(pts
						(arc
							(start -0.1778 -0.2794)
							(mid -0.249642 -0.249642)
							(end -0.2794 -0.1778)
						)
						(arc
							(start -0.2794 0.1778)
							(mid -0.249642 0.249642)
							(end -0.1778 0.2794)
						)
						(arc
							(start 0.1778 0.2794)
							(mid 0.249642 0.249642)
							(end 0.2794 0.1778)
						)
						(arc
							(start 0.2794 -0.1778)
							(mid 0.249642 -0.249642)
							(end 0.1778 -0.2794)
						)
					)
					(width 0)
					(fill yes)
				)
			)
		)
	)
	(footprint ""
		(layer "F.Cu")
		(at 66.802 -172.085)
		(property "Reference" "C34"
			(at 0 0 0)
			(layer "F.SilkS")
			(hide yes)
			(effects
				(font
					(size 1.27 1.27)
				)
			)
		)
		(property "Value" "SCD1U16V2KX-3GP"
			(at 1.1811 -2.7051 0)
			(unlocked yes)
			(layer "F.Fab")
			(hide yes)
			(effects
				(font
					(size 1.016 1.016)
					(thickness 0.1524)
				)
			)
		)
		(property "Device Type" "C402H22"
			(at 1.1811 -4.2291 0)
			(unlocked yes)
			(layer "F.Fab")
			(hide yes)
			(effects
				(font
					(size 1.016 1.016)
					(thickness 0.1524)
				)
			)
		)
		(duplicate_pad_numbers_are_jumpers no)
		(fp_rect
			(start -0.4318 0.9525)
			(end 0.4318 -0.9525)
			(stroke
				(width 0)
				(type default)
			)
			(fill no)
			(layer "F.CrtYd")
		)
		(fp_rect
			(start -0.4318 0.9525)
			(end 0.4318 -0.9525)
			(stroke
				(width 0)
				(type default)
			)
			(fill no)
			(layer "F.Fab")
		)
		(pad "1" smd custom
			(at 0 -0.4445)
			(size 0.1524 0.1524)
			(layers "F.Cu" "F.Mask" "F.Paste")
			(net "P5V_STBY")
			(options
				(clearance outline)
				(anchor circle)
			)
			(primitives
				(gr_poly
					(pts
						(arc
							(start 0.3048 -0.2032)
							(mid 0.275042 -0.275042)
							(end 0.2032 -0.3048)
						)
						(arc
							(start -0.2032 -0.3048)
							(mid -0.275042 -0.275042)
							(end -0.3048 -0.2032)
						)
						(arc
							(start -0.3048 0.2032)
							(mid -0.275042 0.275042)
							(end -0.2032 0.3048)
						)
						(arc
							(start 0.2032 0.3048)
							(mid 0.275042 0.275042)
							(end 0.3048 0.2032)
						)
					)
					(width 0)
					(fill yes)
				)
			)
		)
		(pad "2" smd custom
			(at 0 0.4445)
			(size 0.1524 0.1524)
			(layers "F.Cu" "F.Mask" "F.Paste")
			(net "GND")
			(options
				(clearance outline)
				(anchor circle)
			)
			(primitives
				(gr_poly
					(pts
						(arc
							(start 0.3048 -0.2032)
							(mid 0.275042 -0.275042)
							(end 0.2032 -0.3048)
						)
						(arc
							(start -0.2032 -0.3048)
							(mid -0.275042 -0.275042)
							(end -0.3048 -0.2032)
						)
						(arc
							(start -0.3048 0.2032)
							(mid -0.275042 0.275042)
							(end -0.2032 0.3048)
						)
						(arc
							(start 0.2032 0.3048)
							(mid 0.275042 0.275042)
							(end 0.3048 0.2032)
						)
					)
					(width 0)
					(fill yes)
				)
			)
		)
	)
)
